# T6G (Grand Teton) — schematic netlist excerpt (pin names and nets, part order shuffled) for the footprints in the layout excerpt that follows; sources: Cadence DE-HDL packaged netlist, KiCad conversion of 04192023_DAF0TMB3IC0_F0TG_MB_C_brd_V02_OCP.brd

PC2183  Q_CAP  220PF 50V 10% EMPTY  pkg 0402  page 263 : A = HSC_ON ; B = AGND_HSC
R9004  Q_RES  4.7K 5% CHIP  pkg 0402LF  page 123 : A = P3V3_AUX ; B = PRSNT_CABLE_SWB_B1

(kicad_pcb
	(version 20260206)
	(generator "pcbnew")
	(generator_version "10.0")
	(general
		(thickness 1.6)
		(legacy_teardrops no)
	)
	(paper "A4")
	(title_block
		(title "04192023_DAF0TMB3IC0_F0TG_MB_C_brd_V02_OCP.brd")
		(comment 1 "Grand Teton / footprints 2917-2918 of 8354")
	)
	(layers
		(0 "F.Cu" signal "TOP")
		(4 "In1.Cu" signal "GND")
		(6 "In2.Cu" signal "IN1")
		(8 "In3.Cu" signal "GND1")
		(10 "In4.Cu" signal "IN2")
		(12 "In5.Cu" signal "GND2")
		(14 "In6.Cu" signal "IN3")
		(16 "In7.Cu" signal "GND3")
		(18 "In8.Cu" signal "VCC")
		(20 "In9.Cu" signal "VCC1")
		(22 "In10.Cu" signal "GND4")
		(24 "In11.Cu" signal "IN4")
		(26 "In12.Cu" signal "GND5")
		(28 "In13.Cu" signal "IN5")
		(30 "In14.Cu" signal "GND6")
		(32 "In15.Cu" signal "IN6")
		(34 "In16.Cu" signal "GND7")
		(2 "B.Cu" signal "BOTTOM")
		(9 "F.Adhes" user "F.Adhesive")
		(11 "B.Adhes" user "B.Adhesive")
		(13 "F.Paste" user "Package Geometry/Pastemask Top")
		(15 "B.Paste" user "Package Geometry/Pastemask Bottom")
		(5 "F.SilkS" user "Ref Des/Silkscreen Top")
		(7 "B.SilkS" user "Ref Des/Silkscreen Bottom")
		(1 "F.Mask" user "Board Geometry/Soldermask Top")
		(3 "B.Mask" user "Board Geometry/Soldermask Bottom")
		(17 "Dwgs.User" user "User.Drawings")
		(19 "Cmts.User" user "User.Comments")
		(21 "Eco1.User" user "User.Eco1")
		(23 "Eco2.User" user "User.Eco2")
		(25 "Edge.Cuts" user "Board Geometry/Outline")
		(27 "Margin" user)
		(31 "F.CrtYd" user "Package Geometry/Place Bound Top")
		(29 "B.CrtYd" user "Package Geometry/Place Bound Bottom")
		(35 "F.Fab" user "Ref Des/Assembly Top")
		(33 "B.Fab" user "Ref Des/Assembly Bottom")
	)
	(footprint ""
		(layer "F.Cu")
		(at 215.4301 -404.020782)
		(property "Reference" "PC2183"
			(at 0 0 0)
			(layer "F.SilkS")
			(hide yes)
			(effects
				(font
					(size 1.27 1.27)
				)
			)
		)
		(property "Value" ""
			(at 0 0 0)
			(layer "F.Fab")
			(effects
				(font
					(size 1.27 1.27)
				)
			)
		)
		(duplicate_pad_numbers_are_jumpers no)
		(fp_line
			(start -0.7874 -0.4064)
			(end 0.7874 -0.4064)
			(stroke
				(width 0.1524)
				(type default)
			)
			(layer "F.SilkS")
		)
		(fp_line
			(start -0.7874 0.4064)
			(end -0.7874 -0.4064)
			(stroke
				(width 0.1524)
				(type default)
			)
			(layer "F.SilkS")
		)
		(fp_line
			(start 0.7874 -0.4064)
			(end 0.7874 0.4064)
			(stroke
				(width 0.1524)
				(type default)
			)
			(layer "F.SilkS")
		)
		(fp_line
			(start 0.7874 0.4064)
			(end -0.7874 0.4064)
			(stroke
				(width 0.1524)
				(type default)
			)
			(layer "F.SilkS")
		)
		(fp_line
			(start -0.67945 -0.305054)
			(end -0.12065 -0.305054)
			(stroke
				(width 0.1)
				(type default)
			)
			(layer "F.Fab")
		)
		(fp_line
			(start -0.67945 0.3048)
			(end -0.67945 -0.305054)
			(stroke
				(width 0.1)
				(type default)
			)
			(layer "F.Fab")
		)
		(fp_line
			(start -0.12065 -0.305054)
			(end -0.12065 -0.2794)
			(stroke
				(width 0.1)
				(type default)
			)
			(layer "F.Fab")
		)
		(fp_line
			(start -0.12065 -0.2794)
			(end 0.12065 -0.2794)
			(stroke
				(width 0.1)
				(type default)
			)
			(layer "F.Fab")
		)
		(fp_line
			(start -0.12065 0.2794)
			(end -0.12065 0.3048)
			(stroke
				(width 0.1)
				(type default)
			)
			(layer "F.Fab")
		)
		(fp_line
			(start -0.12065 0.3048)
			(end -0.67945 0.3048)
			(stroke
				(width 0.1)
				(type default)
			)
			(layer "F.Fab")
		)
		(fp_line
			(start 0.120396 0.2794)
			(end -0.12065 0.2794)
			(stroke
				(width 0.1)
				(type default)
			)
			(layer "F.Fab")
		)
		(fp_line
			(start 0.120396 0.3048)
			(end 0.120396 0.2794)
			(stroke
				(width 0.1)
				(type default)
			)
			(layer "F.Fab")
		)
		(fp_line
			(start 0.12065 -0.3048)
			(end 0.67945 -0.3048)
			(stroke
				(width 0.1)
				(type default)
			)
			(layer "F.Fab")
		)
		(fp_line
			(start 0.12065 -0.2794)
			(end 0.12065 -0.3048)
			(stroke
				(width 0.1)
				(type default)
			)
			(layer "F.Fab")
		)
		(fp_line
			(start 0.67945 -0.3048)
			(end 0.67945 0.3048)
			(stroke
				(width 0.1)
				(type default)
			)
			(layer "F.Fab")
		)
		(fp_line
			(start 0.67945 0.3048)
			(end 0.120396 0.3048)
			(stroke
				(width 0.1)
				(type default)
			)
			(layer "F.Fab")
		)
		(pad "1" smd circle
			(at -0.40005 0)
			(size 0 0)
			(layers "F.Cu" "F.Mask" "F.Paste")
			(net "HSC_ON")
		)
		(pad "2" smd circle
			(at 0.40005 0)
			(size 0 0)
			(layers "F.Cu" "F.Mask" "F.Paste")
			(net "AGND_HSC")
		)
	)
	(footprint ""
		(layer "F.Cu")
		(at 363.318044 -418.360098 180)
		(property "Reference" "R9004"
			(at 0 0 180)
			(layer "F.SilkS")
			(hide yes)
			(effects
				(font
					(size 1.27 1.27)
				)
			)
		)
		(property "Value" ""
			(at 0 0 180)
			(layer "F.Fab")
			(effects
				(font
					(size 1.27 1.27)
				)
			)
		)
		(duplicate_pad_numbers_are_jumpers no)
		(fp_line
			(start 0.7874 0.4064)
			(end -0.7874 0.4064)
			(stroke
				(width 0.1524)
				(type default)
			)
			(layer "F.SilkS")
		)
		(fp_line
			(start 0.7874 -0.4064)
			(end 0.7874 0.4064)
			(stroke
				(width 0.1524)
				(type default)
			)
			(layer "F.SilkS")
		)
		(fp_line
			(start -0.7874 0.4064)
			(end -0.7874 -0.4064)
			(stroke
				(width 0.1524)
				(type default)
			)
			(layer "F.SilkS")
		)
		(fp_line
			(start -0.7874 -0.4064)
			(end 0.7874 -0.4064)
			(stroke
				(width 0.1524)
				(type default)
			)
			(layer "F.SilkS")
		)
		(fp_line
			(start 0.67945 0.3048)
			(end 0.120396 0.3048)
			(stroke
				(width 0.1)
				(type default)
			)
			(layer "F.Fab")
		)
		(fp_line
			(start 0.67945 -0.3048)
			(end 0.67945 0.3048)
			(stroke
				(width 0.1)
				(type default)
			)
			(layer "F.Fab")
		)
		(fp_line
			(start 0.12065 -0.2794)
			(end 0.12065 -0.3048)
			(stroke
				(width 0.1)
				(type default)
			)
			(layer "F.Fab")
		)
		(fp_line
			(start 0.12065 -0.3048)
			(end 0.67945 -0.3048)
			(stroke
				(width 0.1)
				(type default)
			)
			(layer "F.Fab")
		)
		(fp_line
			(start 0.120396 0.3048)
			(end 0.120396 0.2794)
			(stroke
				(width 0.1)
				(type default)
			)
			(layer "F.Fab")
		)
		(fp_line
			(start 0.120396 0.2794)
			(end -0.12065 0.2794)
			(stroke
				(width 0.1)
				(type default)
			)
			(layer "F.Fab")
		)
		(fp_line
			(start -0.12065 0.3048)
			(end -0.67945 0.3048)
			(stroke
				(width 0.1)
				(type default)
			)
			(layer "F.Fab")
		)
		(fp_line
			(start -0.12065 0.2794)
			(end -0.12065 0.3048)
			(stroke
				(width 0.1)
				(type default)
			)
			(layer "F.Fab")
		)
		(fp_line
			(start -0.12065 -0.2794)
			(end 0.12065 -0.2794)
			(stroke
				(width 0.1)
				(type default)
			)
			(layer "F.Fab")
		)
		(fp_line
			(start -0.12065 -0.305054)
			(end -0.12065 -0.2794)
			(stroke
				(width 0.1)
				(type default)
			)
			(layer "F.Fab")
		)
		(fp_line
			(start -0.67945 0.3048)
			(end -0.67945 -0.305054)
			(stroke
				(width 0.1)
				(type default)
			)
			(layer "F.Fab")
		)
		(fp_line
			(start -0.67945 -0.305054)
			(end -0.12065 -0.305054)
			(stroke
				(width 0.1)
				(type default)
			)
			(layer "F.Fab")
		)
		(pad "1" smd circle
			(at -0.40005 0 180)
			(size 0 0)
			(layers "F.Cu" "F.Mask" "F.Paste")
			(net "P3V3_AUX")
		)
		(pad "2" smd circle
			(at 0.40005 0 180)
			(size 0 0)
			(layers "F.Cu" "F.Mask" "F.Paste")
			(net "PRSNT_CABLE_SWB_B1")
		)
	)
)
